(kicad_pcb
	(version 20260206)
	(generator "pcbnew")
	(generator_version "10.0")
	(general
		(thickness 1.6)
		(legacy_teardrops no)
	)
	(paper "A4")
	(title_block
		(title "04192023_DAF0TMB3IC0_F0TG_MB_C_brd_V02_OCP.brd")
		(comment 1 "Grand Teton / footprints 2351-2351 of 8354")
	)
	(layers
		(0 "F.Cu" signal "TOP")
		(4 "In1.Cu" signal "GND")
		(6 "In2.Cu" signal "IN1")
		(8 "In3.Cu" signal "GND1")
		(10 "In4.Cu" signal "IN2")
		(12 "In5.Cu" signal "GND2")
		(14 "In6.Cu" signal "IN3")
		(16 "In7.Cu" signal "GND3")
		(18 "In8.Cu" signal "VCC")
		(20 "In9.Cu" signal "VCC1")
		(22 "In10.Cu" signal "GND4")
		(24 "In11.Cu" signal "IN4")
		(26 "In12.Cu" signal "GND5")
		(28 "In13.Cu" signal "IN5")
		(30 "In14.Cu" signal "GND6")
		(32 "In15.Cu" signal "IN6")
		(34 "In16.Cu" signal "GND7")
		(2 "B.Cu" signal "BOTTOM")
		(9 "F.Adhes" user "F.Adhesive")
		(11 "B.Adhes" user "B.Adhesive")
		(13 "F.Paste" user "Package Geometry/Pastemask Top")
		(15 "B.Paste" user "Package Geometry/Pastemask Bottom")
		(5 "F.SilkS" user "Ref Des/Silkscreen Top")
		(7 "B.SilkS" user "Ref Des/Silkscreen Bottom")
		(1 "F.Mask" user "Board Geometry/Soldermask Top")
		(3 "B.Mask" user "Board Geometry/Soldermask Bottom")
		(17 "Dwgs.User" user "User.Drawings")
		(19 "Cmts.User" user "User.Comments")
		(21 "Eco1.User" user "User.Eco1")
		(23 "Eco2.User" user "User.Eco2")
		(25 "Edge.Cuts" user "Board Geometry/Outline")
		(27 "Margin" user)
		(31 "F.CrtYd" user "Package Geometry/Place Bound Top")
		(29 "B.CrtYd" user "Package Geometry/Place Bound Bottom")
		(35 "F.Fab" user "Ref Des/Assembly Top")
		(33 "B.Fab" user "Ref Des/Assembly Bottom")
	)
	(footprint ""
		(layer "F.Cu")
		(at 40.494458 -429.790098 -90)
		(property "Reference" "R3265"
			(at 0 0 270)
			(layer "F.SilkS")
			(hide yes)
			(effects
				(font
					(size 1.27 1.27)
				)
			)
		)
		(property "Value" ""
			(at 0 0 270)
			(layer "F.Fab")
			(effects
				(font
					(size 1.27 1.27)
				)
			)
		)
		(duplicate_pad_numbers_are_jumpers no)
		(fp_line
			(start -0.7874 0.4064)
			(end -0.7874 -0.4064)
			(stroke
				(width 0.1524)
				(type default)
			)
			(layer "F.SilkS")
		)
		(fp_line
			(start 0.7874 0.4064)
			(end -0.7874 0.4064)
			(stroke
				(width 0.1524)
				(type default)
			)
			(layer "F.SilkS")
		)
		(fp_line
			(start -0.7874 -0.4064)
			(end 0.7874 -0.4064)
			(stroke
				(width 0.1524)
				(type default)
			)
			(layer "F.SilkS")
		)
		(fp_line
			(start 0.7874 -0.4064)
			(end 0.7874 0.4064)
			(stroke
				(width 0.1524)
				(type default)
			)
			(layer "F.SilkS")
		)
		(fp_line
			(start -0.67945 0.3048)
			(end -0.67945 -0.305054)
			(stroke
				(width 0.1)
				(type default)
			)
			(layer "F.Fab")
		)
		(fp_line
			(start -0.12065 0.3048)
			(end -0.67945 0.3048)
			(stroke
				(width 0.1)
				(type default)
			)
			(layer "F.Fab")
		)
		(fp_line
			(start 0.120396 0.3048)
			(end 0.120396 0.2794)
			(stroke
				(width 0.1)
				(type default)
			)
			(layer "F.Fab")
		)
		(fp_line
			(start 0.67945 0.3048)
			(end 0.120396 0.3048)
			(stroke
				(width 0.1)
				(type default)
			)
			(layer "F.Fab")
		)
		(fp_line
			(start -0.12065 0.2794)
			(end -0.12065 0.3048)
			(stroke
				(width 0.1)
				(type default)
			)
			(layer "F.Fab")
		)
		(fp_line
			(start 0.120396 0.2794)
			(end -0.12065 0.2794)
			(stroke
				(width 0.1)
				(type default)
			)
			(layer "F.Fab")
		)
		(fp_line
			(start -0.12065 -0.2794)
			(end 0.12065 -0.2794)
			(stroke
				(width 0.1)
				(type default)
			)
			(layer "F.Fab")
		)
		(fp_line
			(start 0.12065 -0.2794)
			(end 0.12065 -0.3048)
			(stroke
				(width 0.1)
				(type default)
			)
			(layer "F.Fab")
		)
		(fp_line
			(start 0.12065 -0.3048)
			(end 0.67945 -0.3048)
			(stroke
				(width 0.1)
				(type default)
			)
			(layer "F.Fab")
		)
		(fp_line
			(start 0.67945 -0.3048)
			(end 0.67945 0.3048)
			(stroke
				(width 0.1)
				(type default)
			)
			(layer "F.Fab")
		)
		(fp_line
			(start -0.67945 -0.305054)
			(end -0.12065 -0.305054)
			(stroke
				(width 0.1)
				(type default)
			)
			(layer "F.Fab")
		)
		(fp_line
			(start -0.12065 -0.305054)
			(end -0.12065 -0.2794)
			(stroke
				(width 0.1)
				(type default)
			)
			(layer "F.Fab")
		)
		(pad "1" smd circle
			(at -0.40005 0 270)
			(size 0 0)
			(layers "F.Cu" "F.Mask" "F.Paste")
			(net "CLK_GEN2_GPU_FPGA_OE_OR_N")
		)
		(pad "2" smd circle
			(at 0.40005 0 270)
			(size 0 0)
			(layers "F.Cu" "F.Mask" "F.Paste")
			(net "GND")
		)
	)
)
